(kicad_pcb
	(version 20260206)
	(generator "pcbnew")
	(generator_version "10.0")
	(general
		(thickness 1.6)
		(legacy_teardrops no)
	)
	(paper "A4")
	(title_block
		(title "01162023_DA0F0TEBIF0_F0T_Expander_BD_F_brd_V02_OCP.brd")
		(comment 1 "Grand Teton / footprints 7776-7783 of 9728")
	)
	(layers
		(0 "F.Cu" signal "TOP")
		(4 "In1.Cu" signal "GND")
		(6 "In2.Cu" signal "VCC")
		(8 "In3.Cu" signal "VCC1")
		(10 "In4.Cu" signal "GND1")
		(12 "In5.Cu" signal "IN1")
		(14 "In6.Cu" signal "GND2")
		(16 "In7.Cu" signal "IN2")
		(18 "In8.Cu" signal "GND3")
		(20 "In9.Cu" signal "IN3")
		(22 "In10.Cu" signal "GND4")
		(24 "In11.Cu" signal "IN4")
		(26 "In12.Cu" signal "GND5")
		(28 "In13.Cu" signal "IN5")
		(30 "In14.Cu" signal "GND6")
		(32 "In15.Cu" signal "IN6")
		(34 "In16.Cu" signal "GND7")
		(2 "B.Cu" signal "BOTTOM")
		(9 "F.Adhes" user "F.Adhesive")
		(11 "B.Adhes" user "B.Adhesive")
		(13 "F.Paste" user "Package Geometry/Pastemask Top")
		(15 "B.Paste" user "Package Geometry/Pastemask Bottom")
		(5 "F.SilkS" user "Ref Des/Silkscreen Top")
		(7 "B.SilkS" user "Ref Des/Silkscreen Bottom")
		(1 "F.Mask" user "Board Geometry/Soldermask Top")
		(3 "B.Mask" user "Board Geometry/Soldermask Bottom")
		(17 "Dwgs.User" user "User.Drawings")
		(19 "Cmts.User" user "User.Comments")
		(21 "Eco1.User" user "User.Eco1")
		(23 "Eco2.User" user "User.Eco2")
		(25 "Edge.Cuts" user "Board Geometry/Outline")
		(27 "Margin" user)
		(31 "F.CrtYd" user "Package Geometry/Place Bound Top")
		(29 "B.CrtYd" user "Package Geometry/Place Bound Bottom")
		(35 "F.Fab" user "Ref Des/Assembly Top")
		(33 "B.Fab" user "Ref Des/Assembly Bottom")
	)
	(footprint ""
		(layer "B.Cu")
		(at 346.016326 -326.945498 -90)
		(property "Reference" "C4325"
			(at 0 0 90)
			(layer "B.SilkS")
			(hide yes)
			(effects
				(font
					(size 1.27 1.27)
				)
				(justify mirror)
			)
		)
		(property "Value" ""
			(at 0 0 90)
			(layer "B.Fab")
			(effects
				(font
					(size 1.27 1.27)
				)
				(justify mirror)
			)
		)
		(duplicate_pad_numbers_are_jumpers no)
		(fp_line
			(start -1.2954 0.5842)
			(end 1.2954 0.5842)
			(stroke
				(width 0.1524)
				(type default)
			)
			(layer "B.SilkS")
		)
		(fp_line
			(start 1.2954 0.5842)
			(end 1.2954 -0.5842)
			(stroke
				(width 0.1524)
				(type default)
			)
			(layer "B.SilkS")
		)
		(fp_line
			(start -1.2954 -0.5842)
			(end -1.2954 0.5842)
			(stroke
				(width 0.1524)
				(type default)
			)
			(layer "B.SilkS")
		)
		(fp_line
			(start 1.2954 -0.5842)
			(end -1.2954 -0.5842)
			(stroke
				(width 0.1524)
				(type default)
			)
			(layer "B.SilkS")
		)
		(fp_line
			(start -0.8636 0.4572)
			(end 0.8636 0.4572)
			(stroke
				(width 0.1)
				(type default)
			)
			(layer "B.Fab")
		)
		(fp_line
			(start 0.8636 0.4572)
			(end 0.8636 0.4064)
			(stroke
				(width 0.1)
				(type default)
			)
			(layer "B.Fab")
		)
		(fp_line
			(start -1.1938 0.4064)
			(end -0.8636 0.4064)
			(stroke
				(width 0.1)
				(type default)
			)
			(layer "B.Fab")
		)
		(fp_line
			(start -0.8636 0.4064)
			(end -0.8636 0.4572)
			(stroke
				(width 0.1)
				(type default)
			)
			(layer "B.Fab")
		)
		(fp_line
			(start 0.8636 0.4064)
			(end 1.1938 0.4064)
			(stroke
				(width 0.1)
				(type default)
			)
			(layer "B.Fab")
		)
		(fp_line
			(start 1.1938 0.4064)
			(end 1.1938 -0.4064)
			(stroke
				(width 0.1)
				(type default)
			)
			(layer "B.Fab")
		)
		(fp_line
			(start -1.1938 -0.4064)
			(end -1.1938 0.4064)
			(stroke
				(width 0.1)
				(type default)
			)
			(layer "B.Fab")
		)
		(fp_line
			(start -0.8636 -0.4064)
			(end -1.1938 -0.4064)
			(stroke
				(width 0.1)
				(type default)
			)
			(layer "B.Fab")
		)
		(fp_line
			(start 0.8636 -0.4064)
			(end 0.8636 -0.4572)
			(stroke
				(width 0.1)
				(type default)
			)
			(layer "B.Fab")
		)
		(fp_line
			(start 1.1938 -0.4064)
			(end 0.8636 -0.4064)
			(stroke
				(width 0.1)
				(type default)
			)
			(layer "B.Fab")
		)
		(fp_line
			(start -0.8636 -0.4572)
			(end -0.8636 -0.4064)
			(stroke
				(width 0.1)
				(type default)
			)
			(layer "B.Fab")
		)
		(fp_line
			(start 0.8636 -0.4572)
			(end -0.8636 -0.4572)
			(stroke
				(width 0.1)
				(type default)
			)
			(layer "B.Fab")
		)
		(pad "1" smd rect
			(at 0.7366 0 180)
			(size 0.7112 0.8128)
			(layers "B.Cu" "B.Mask" "B.Paste")
			(net "P0V8_SERDES_VDDA_PEX2_C7")
		)
		(pad "2" smd rect
			(at -0.7366 0 180)
			(size 0.7112 0.8128)
			(layers "B.Cu" "B.Mask" "B.Paste")
			(net "GND")
		)
	)
	(footprint ""
		(layer "B.Cu")
		(at 292.651942 -296.3926 180)
		(property "Reference" "C1637"
			(at 0 0 0)
			(layer "B.SilkS")
			(hide yes)
			(effects
				(font
					(size 1.27 1.27)
				)
				(justify mirror)
			)
		)
		(property "Value" ""
			(at 0 0 0)
			(layer "B.Fab")
			(effects
				(font
					(size 1.27 1.27)
				)
				(justify mirror)
			)
		)
		(duplicate_pad_numbers_are_jumpers no)
		(fp_line
			(start 0.299974 0.150114)
			(end 0.299974 -0.150114)
			(stroke
				(width 0.1)
				(type default)
			)
			(layer "B.Fab")
		)
		(fp_line
			(start 0.299974 -0.150114)
			(end -0.299974 -0.150114)
			(stroke
				(width 0.1)
				(type default)
			)
			(layer "B.Fab")
		)
		(fp_line
			(start -0.299974 0.150114)
			(end 0.299974 0.150114)
			(stroke
				(width 0.1)
				(type default)
			)
			(layer "B.Fab")
		)
		(fp_line
			(start -0.299974 -0.150114)
			(end -0.299974 0.150114)
			(stroke
				(width 0.1)
				(type default)
			)
			(layer "B.Fab")
		)
		(pad "1" smd rect
			(at 0.2667 0)
			(size 0.3048 0.381)
			(layers "B.Cu" "B.Mask" "B.Paste")
			(net "P0V8_PEX2")
		)
		(pad "2" smd rect
			(at -0.2667 0)
			(size 0.3048 0.381)
			(layers "B.Cu" "B.Mask" "B.Paste")
			(net "GND")
		)
	)
	(footprint ""
		(layer "B.Cu")
		(at 238.61649 -208.886552 -90)
		(property "Reference" "L147"
			(at 0 0 90)
			(layer "B.SilkS")
			(hide yes)
			(effects
				(font
					(size 1.27 1.27)
				)
				(justify mirror)
			)
		)
		(property "Value" ""
			(at 0 0 90)
			(layer "B.Fab")
			(effects
				(font
					(size 1.27 1.27)
				)
				(justify mirror)
			)
		)
		(duplicate_pad_numbers_are_jumpers no)
		(fp_line
			(start -1.27 0.5842)
			(end 1.27 0.5842)
			(stroke
				(width 0.1524)
				(type default)
			)
			(layer "B.SilkS")
		)
		(fp_line
			(start -1.27 0.5842)
			(end -1.27 -0.5842)
			(stroke
				(width 0.1524)
				(type default)
			)
			(layer "B.SilkS")
		)
		(fp_line
			(start 1.27 0.5842)
			(end 1.27 -0.5842)
			(stroke
				(width 0.1524)
				(type default)
			)
			(layer "B.SilkS")
		)
		(fp_line
			(start 1.27 -0.5588)
			(end 1.27 -0.5842)
			(stroke
				(width 0.1524)
				(type default)
			)
			(layer "B.SilkS")
		)
		(fp_line
			(start 1.27 -0.5842)
			(end -1.27 -0.5842)
			(stroke
				(width 0.1524)
				(type default)
			)
			(layer "B.SilkS")
		)
		(fp_line
			(start -0.9144 0.508)
			(end 0.9144 0.508)
			(stroke
				(width 0.1)
				(type default)
			)
			(layer "B.Fab")
		)
		(fp_line
			(start 0.9144 0.508)
			(end 0.9144 0.406654)
			(stroke
				(width 0.1)
				(type default)
			)
			(layer "B.Fab")
		)
		(fp_line
			(start 0.9144 0.406654)
			(end 1.194308 0.406654)
			(stroke
				(width 0.1)
				(type default)
			)
			(layer "B.Fab")
		)
		(fp_line
			(start 1.194308 0.406654)
			(end 1.194308 -0.406654)
			(stroke
				(width 0.1)
				(type default)
			)
			(layer "B.Fab")
		)
		(fp_line
			(start -1.1938 0.4064)
			(end -0.9144 0.4064)
			(stroke
				(width 0.1)
				(type default)
			)
			(layer "B.Fab")
		)
		(fp_line
			(start -0.9144 0.4064)
			(end -0.9144 0.508)
			(stroke
				(width 0.1)
				(type default)
			)
			(layer "B.Fab")
		)
		(fp_line
			(start -1.1938 -0.406654)
			(end -1.1938 0.4064)
			(stroke
				(width 0.1)
				(type default)
			)
			(layer "B.Fab")
		)
		(fp_line
			(start -0.9144 -0.406654)
			(end -1.1938 -0.406654)
			(stroke
				(width 0.1)
				(type default)
			)
			(layer "B.Fab")
		)
		(fp_line
			(start 0.9144 -0.406654)
			(end 0.9144 -0.508)
			(stroke
				(width 0.1)
				(type default)
			)
			(layer "B.Fab")
		)
		(fp_line
			(start 1.194308 -0.406654)
			(end 0.9144 -0.406654)
			(stroke
				(width 0.1)
				(type default)
			)
			(layer "B.Fab")
		)
		(fp_line
			(start -0.9144 -0.508)
			(end -0.9144 -0.406654)
			(stroke
				(width 0.1)
				(type default)
			)
			(layer "B.Fab")
		)
		(fp_line
			(start 0.9144 -0.508)
			(end -0.9144 -0.508)
			(stroke
				(width 0.1)
				(type default)
			)
			(layer "B.Fab")
		)
		(pad "1" smd rect
			(at 0.7366 0 180)
			(size 0.7112 0.8128)
			(layers "B.Cu" "B.Mask" "B.Paste")
			(net "P3V3_AUX")
		)
		(pad "2" smd rect
			(at -0.7366 0 180)
			(size 0.7112 0.8128)
			(layers "B.Cu" "B.Mask" "B.Paste")
			(net "P3V3_BIC_USB2AV33")
		)
	)
	(footprint ""
		(layer "B.Cu")
		(at 181.44998 -292.099746 90)
		(property "Reference" "C1422"
			(at 0 0 90)
			(layer "B.SilkS")
			(hide yes)
			(effects
				(font
					(size 1.27 1.27)
				)
				(justify mirror)
			)
		)
		(property "Value" ""
			(at 0 0 90)
			(layer "B.Fab")
			(effects
				(font
					(size 1.27 1.27)
				)
				(justify mirror)
			)
		)
		(duplicate_pad_numbers_are_jumpers no)
		(fp_line
			(start 0.299974 -0.150114)
			(end -0.299974 -0.150114)
			(stroke
				(width 0.1)
				(type default)
			)
			(layer "B.Fab")
		)
		(fp_line
			(start -0.299974 -0.150114)
			(end -0.299974 0.150114)
			(stroke
				(width 0.1)
				(type default)
			)
			(layer "B.Fab")
		)
		(fp_line
			(start 0.299974 0.150114)
			(end 0.299974 -0.150114)
			(stroke
				(width 0.1)
				(type default)
			)
			(layer "B.Fab")
		)
		(fp_line
			(start -0.299974 0.150114)
			(end 0.299974 0.150114)
			(stroke
				(width 0.1)
				(type default)
			)
			(layer "B.Fab")
		)
		(pad "1" smd rect
			(at 0.2667 0 270)
			(size 0.3048 0.381)
			(layers "B.Cu" "B.Mask" "B.Paste")
			(net "P0V8_SERDES_VDDA_PEX1")
		)
		(pad "2" smd rect
			(at -0.2667 0 270)
			(size 0.3048 0.381)
			(layers "B.Cu" "B.Mask" "B.Paste")
			(net "GND")
		)
	)
	(footprint ""
		(layer "B.Cu")
		(at 75.72375 -289.724846 90)
		(property "Reference" "R933"
			(at 0 0 90)
			(layer "B.SilkS")
			(hide yes)
			(effects
				(font
					(size 1.27 1.27)
				)
				(justify mirror)
			)
		)
		(property "Value" ""
			(at 0 0 90)
			(layer "B.Fab")
			(effects
				(font
					(size 1.27 1.27)
				)
				(justify mirror)
			)
		)
		(duplicate_pad_numbers_are_jumpers no)
		(fp_line
			(start 0.7874 -0.4064)
			(end -0.7874 -0.4064)
			(stroke
				(width 0.1524)
				(type default)
			)
			(layer "B.SilkS")
		)
		(fp_line
			(start -0.7874 -0.4064)
			(end -0.7874 0.4064)
			(stroke
				(width 0.1524)
				(type default)
			)
			(layer "B.SilkS")
		)
		(fp_line
			(start 0.7874 0.4064)
			(end 0.7874 -0.4064)
			(stroke
				(width 0.1524)
				(type default)
			)
			(layer "B.SilkS")
		)
		(fp_line
			(start -0.7874 0.4064)
			(end 0.7874 0.4064)
			(stroke
				(width 0.1524)
				(type default)
			)
			(layer "B.SilkS")
		)
		(fp_line
			(start 0.67945 -0.305054)
			(end 0.12065 -0.305054)
			(stroke
				(width 0.1)
				(type default)
			)
			(layer "B.Fab")
		)
		(fp_line
			(start 0.12065 -0.305054)
			(end 0.12065 -0.2794)
			(stroke
				(width 0.1)
				(type default)
			)
			(layer "B.Fab")
		)
		(fp_line
			(start -0.12065 -0.3048)
			(end -0.67945 -0.3048)
			(stroke
				(width 0.1)
				(type default)
			)
			(layer "B.Fab")
		)
		(fp_line
			(start -0.67945 -0.3048)
			(end -0.67945 0.3048)
			(stroke
				(width 0.1)
				(type default)
			)
			(layer "B.Fab")
		)
		(fp_line
			(start 0.12065 -0.2794)
			(end -0.12065 -0.2794)
			(stroke
				(width 0.1)
				(type default)
			)
			(layer "B.Fab")
		)
		(fp_line
			(start -0.12065 -0.2794)
			(end -0.12065 -0.3048)
			(stroke
				(width 0.1)
				(type default)
			)
			(layer "B.Fab")
		)
		(fp_line
			(start 0.12065 0.2794)
			(end 0.12065 0.3048)
			(stroke
				(width 0.1)
				(type default)
			)
			(layer "B.Fab")
		)
		(fp_line
			(start -0.120396 0.2794)
			(end 0.12065 0.2794)
			(stroke
				(width 0.1)
				(type default)
			)
			(layer "B.Fab")
		)
		(fp_line
			(start 0.67945 0.3048)
			(end 0.67945 -0.305054)
			(stroke
				(width 0.1)
				(type default)
			)
			(layer "B.Fab")
		)
		(fp_line
			(start 0.12065 0.3048)
			(end 0.67945 0.3048)
			(stroke
				(width 0.1)
				(type default)
			)
			(layer "B.Fab")
		)
		(fp_line
			(start -0.120396 0.3048)
			(end -0.120396 0.2794)
			(stroke
				(width 0.1)
				(type default)
			)
			(layer "B.Fab")
		)
		(fp_line
			(start -0.67945 0.3048)
			(end -0.120396 0.3048)
			(stroke
				(width 0.1)
				(type default)
			)
			(layer "B.Fab")
		)
		(pad "1" smd circle
			(at 0.40005 0 270)
			(size 0 0)
			(layers "B.Cu" "B.Mask" "B.Paste")
			(net "UART_PEX0_SDB_TX")
		)
		(pad "2" smd circle
			(at -0.40005 0 270)
			(size 0 0)
			(layers "B.Cu" "B.Mask" "B.Paste")
			(net "UART_PEX0_SDB_R_TX")
		)
	)
	(footprint ""
		(layer "B.Cu")
		(at 116.27739 -254.55372 180)
		(property "Reference" "PR65"
			(at 0 0 0)
			(layer "B.SilkS")
			(hide yes)
			(effects
				(font
					(size 1.27 1.27)
				)
				(justify mirror)
			)
		)
		(property "Value" ""
			(at 0 0 0)
			(layer "B.Fab")
			(effects
				(font
					(size 1.27 1.27)
				)
				(justify mirror)
			)
		)
		(duplicate_pad_numbers_are_jumpers no)
		(fp_line
			(start 0.7874 0.4064)
			(end 0.7874 -0.4064)
			(stroke
				(width 0.1524)
				(type default)
			)
			(layer "B.SilkS")
		)
		(fp_line
			(start 0.7874 -0.4064)
			(end -0.7874 -0.4064)
			(stroke
				(width 0.1524)
				(type default)
			)
			(layer "B.SilkS")
		)
		(fp_line
			(start -0.7874 0.4064)
			(end 0.7874 0.4064)
			(stroke
				(width 0.1524)
				(type default)
			)
			(layer "B.SilkS")
		)
		(fp_line
			(start -0.7874 -0.4064)
			(end -0.7874 0.4064)
			(stroke
				(width 0.1524)
				(type default)
			)
			(layer "B.SilkS")
		)
		(fp_line
			(start 0.67945 0.3048)
			(end 0.67945 -0.305054)
			(stroke
				(width 0.1)
				(type default)
			)
			(layer "B.Fab")
		)
		(fp_line
			(start 0.67945 -0.305054)
			(end 0.12065 -0.305054)
			(stroke
				(width 0.1)
				(type default)
			)
			(layer "B.Fab")
		)
		(fp_line
			(start 0.12065 0.3048)
			(end 0.67945 0.3048)
			(stroke
				(width 0.1)
				(type default)
			)
			(layer "B.Fab")
		)
		(fp_line
			(start 0.12065 0.2794)
			(end 0.12065 0.3048)
			(stroke
				(width 0.1)
				(type default)
			)
			(layer "B.Fab")
		)
		(fp_line
			(start 0.12065 -0.2794)
			(end -0.12065 -0.2794)
			(stroke
				(width 0.1)
				(type default)
			)
			(layer "B.Fab")
		)
		(fp_line
			(start 0.12065 -0.305054)
			(end 0.12065 -0.2794)
			(stroke
				(width 0.1)
				(type default)
			)
			(layer "B.Fab")
		)
		(fp_line
			(start -0.120396 0.3048)
			(end -0.120396 0.2794)
			(stroke
				(width 0.1)
				(type default)
			)
			(layer "B.Fab")
		)
		(fp_line
			(start -0.120396 0.2794)
			(end 0.12065 0.2794)
			(stroke
				(width 0.1)
				(type default)
			)
			(layer "B.Fab")
		)
		(fp_line
			(start -0.12065 -0.2794)
			(end -0.12065 -0.3048)
			(stroke
				(width 0.1)
				(type default)
			)
			(layer "B.Fab")
		)
		(fp_line
			(start -0.12065 -0.3048)
			(end -0.67945 -0.3048)
			(stroke
				(width 0.1)
				(type default)
			)
			(layer "B.Fab")
		)
		(fp_line
			(start -0.67945 0.3048)
			(end -0.120396 0.3048)
			(stroke
				(width 0.1)
				(type default)
			)
			(layer "B.Fab")
		)
		(fp_line
			(start -0.67945 -0.3048)
			(end -0.67945 0.3048)
			(stroke
				(width 0.1)
				(type default)
			)
			(layer "B.Fab")
		)
		(pad "1" smd circle
			(at 0.40005 0)
			(size 0 0)
			(layers "B.Cu" "B.Mask" "B.Paste")
			(net "P3V3_AUX")
		)
		(pad "2" smd circle
			(at -0.40005 0)
			(size 0 0)
			(layers "B.Cu" "B.Mask" "B.Paste")
			(net "P0V8_PEX0_VDD")
		)
	)
	(footprint ""
		(layer "B.Cu")
		(at 169.120312 -296.37482)
		(property "Reference" "C1364"
			(at 0 0 0)
			(layer "B.SilkS")
			(hide yes)
			(effects
				(font
					(size 1.27 1.27)
				)
				(justify mirror)
			)
		)
		(property "Value" ""
			(at 0 0 0)
			(layer "B.Fab")
			(effects
				(font
					(size 1.27 1.27)
				)
				(justify mirror)
			)
		)
		(duplicate_pad_numbers_are_jumpers no)
		(fp_line
			(start -0.299974 -0.150114)
			(end -0.299974 0.150114)
			(stroke
				(width 0.1)
				(type default)
			)
			(layer "B.Fab")
		)
		(fp_line
			(start -0.299974 0.150114)
			(end 0.299974 0.150114)
			(stroke
				(width 0.1)
				(type default)
			)
			(layer "B.Fab")
		)
		(fp_line
			(start 0.299974 -0.150114)
			(end -0.299974 -0.150114)
			(stroke
				(width 0.1)
				(type default)
			)
			(layer "B.Fab")
		)
		(fp_line
			(start 0.299974 0.150114)
			(end 0.299974 -0.150114)
			(stroke
				(width 0.1)
				(type default)
			)
			(layer "B.Fab")
		)
		(pad "1" smd rect
			(at 0.2667 0 180)
			(size 0.3048 0.381)
			(layers "B.Cu" "B.Mask" "B.Paste")
			(net "P0V8_PEX1")
		)
		(pad "2" smd rect
			(at -0.2667 0 180)
			(size 0.3048 0.381)
			(layers "B.Cu" "B.Mask" "B.Paste")
			(net "GND")
		)
	)
	(footprint ""
		(layer "B.Cu")
		(at 71.290688 -118.711218 180)
		(property "Reference" "R75"
			(at 0 0 0)
			(layer "B.SilkS")
			(hide yes)
			(effects
				(font
					(size 1.27 1.27)
				)
				(justify mirror)
			)
		)
		(property "Value" ""
			(at 0 0 0)
			(layer "B.Fab")
			(effects
				(font
					(size 1.27 1.27)
				)
				(justify mirror)
			)
		)
		(duplicate_pad_numbers_are_jumpers no)
		(fp_line
			(start 0.7874 0.4064)
			(end 0.7874 -0.4064)
			(stroke
				(width 0.1524)
				(type default)
			)
			(layer "B.SilkS")
		)
		(fp_line
			(start 0.7874 -0.4064)
			(end -0.7874 -0.4064)
			(stroke
				(width 0.1524)
				(type default)
			)
			(layer "B.SilkS")
		)
		(fp_line
			(start -0.7874 0.4064)
			(end 0.7874 0.4064)
			(stroke
				(width 0.1524)
				(type default)
			)
			(layer "B.SilkS")
		)
		(fp_line
			(start -0.7874 -0.4064)
			(end -0.7874 0.4064)
			(stroke
				(width 0.1524)
				(type default)
			)
			(layer "B.SilkS")
		)
		(fp_line
			(start 0.67945 0.3048)
			(end 0.67945 -0.305054)
			(stroke
				(width 0.1)
				(type default)
			)
			(layer "B.Fab")
		)
		(fp_line
			(start 0.67945 -0.305054)
			(end 0.12065 -0.305054)
			(stroke
				(width 0.1)
				(type default)
			)
			(layer "B.Fab")
		)
		(fp_line
			(start 0.12065 0.3048)
			(end 0.67945 0.3048)
			(stroke
				(width 0.1)
				(type default)
			)
			(layer "B.Fab")
		)
		(fp_line
			(start 0.12065 0.2794)
			(end 0.12065 0.3048)
			(stroke
				(width 0.1)
				(type default)
			)
			(layer "B.Fab")
		)
		(fp_line
			(start 0.12065 -0.2794)
			(end -0.12065 -0.2794)
			(stroke
				(width 0.1)
				(type default)
			)
			(layer "B.Fab")
		)
		(fp_line
			(start 0.12065 -0.305054)
			(end 0.12065 -0.2794)
			(stroke
				(width 0.1)
				(type default)
			)
			(layer "B.Fab")
		)
		(fp_line
			(start -0.120396 0.3048)
			(end -0.120396 0.2794)
			(stroke
				(width 0.1)
				(type default)
			)
			(layer "B.Fab")
		)
		(fp_line
			(start -0.120396 0.2794)
			(end 0.12065 0.2794)
			(stroke
				(width 0.1)
				(type default)
			)
			(layer "B.Fab")
		)
		(fp_line
			(start -0.12065 -0.2794)
			(end -0.12065 -0.3048)
			(stroke
				(width 0.1)
				(type default)
			)
			(layer "B.Fab")
		)
		(fp_line
			(start -0.12065 -0.3048)
			(end -0.67945 -0.3048)
			(stroke
				(width 0.1)
				(type default)
			)
			(layer "B.Fab")
		)
		(fp_line
			(start -0.67945 0.3048)
			(end -0.120396 0.3048)
			(stroke
				(width 0.1)
				(type default)
			)
			(layer "B.Fab")
		)
		(fp_line
			(start -0.67945 -0.3048)
			(end -0.67945 0.3048)
			(stroke
				(width 0.1)
				(type default)
			)
			(layer "B.Fab")
		)
		(pad "1" smd circle
			(at 0.40005 0)
			(size 0 0)
			(layers "B.Cu" "B.Mask" "B.Paste")
			(net "NIC1_AUX_PWR_EN")
		)
		(pad "2" smd circle
			(at -0.40005 0)
			(size 0 0)
			(layers "B.Cu" "B.Mask" "B.Paste")
			(net "GND")
		)
	)
)
